# S9S_MB_2U (Grand Teton) — schematic netlist excerpt (pin names and nets, part order shuffled) for the footprints in the layout excerpt that follows; sources: Cadence DE-HDL packaged netlist, KiCad conversion of 03242023_DA0F0TMBIJ0_F0T_Motherboard_J_brd_V01_OCP.brd

U94  ADM1086AKSZREEL7  ADM1086AKSZ-REEL7 IC  pkg SC70-6_0-65_2X1-25XA  page 244
  ENIN  = FM_COMP_P3V3_AUX_ENIN
  GND  = GND
  VIN  = FM_COMP_P3V3_AUX_VIN
  ENOUT  = PWRGD_DSW_PWROK_R1
  CEXT  = FM_COMP_P3V3_STBY_CEXT
  VCC  = P3V3_AUX

C2254  Q_CAP  0.1UF 25V 10% X7R  pkg 0402  page 225 : A = P0V62_CPU0_ERRS_U306_VREF ; B = GND

(kicad_pcb
	(version 20260206)
	(generator "pcbnew")
	(generator_version "10.0")
	(general
		(thickness 1.6)
		(legacy_teardrops no)
	)
	(paper "A4")
	(title_block
		(title "03242023_DA0F0TMBIJ0_F0T_Motherboard_J_brd_V01_OCP.brd")
		(comment 1 "Grand Teton / footprints 4099-4100 of 6105")
	)
	(layers
		(0 "F.Cu" signal "TOP")
		(4 "In1.Cu" signal "GND")
		(6 "In2.Cu" signal "IN1")
		(8 "In3.Cu" signal "GND1")
		(10 "In4.Cu" signal "IN2")
		(12 "In5.Cu" signal "GND2")
		(14 "In6.Cu" signal "IN3")
		(16 "In7.Cu" signal "GND3")
		(18 "In8.Cu" signal "VCC")
		(20 "In9.Cu" signal "VCC1")
		(22 "In10.Cu" signal "GND4")
		(24 "In11.Cu" signal "IN4")
		(26 "In12.Cu" signal "GND5")
		(28 "In13.Cu" signal "IN5")
		(30 "In14.Cu" signal "GND6")
		(32 "In15.Cu" signal "IN6")
		(34 "In16.Cu" signal "GND7")
		(2 "B.Cu" signal "BOTTOM")
		(9 "F.Adhes" user "F.Adhesive")
		(11 "B.Adhes" user "B.Adhesive")
		(13 "F.Paste" user "Package Geometry/Pastemask Top")
		(15 "B.Paste" user "Package Geometry/Pastemask Bottom")
		(5 "F.SilkS" user "Ref Des/Silkscreen Top")
		(7 "B.SilkS" user "Ref Des/Silkscreen Bottom")
		(1 "F.Mask" user "Board Geometry/Soldermask Top")
		(3 "B.Mask" user "Board Geometry/Soldermask Bottom")
		(17 "Dwgs.User" user "User.Drawings")
		(19 "Cmts.User" user "User.Comments")
		(21 "Eco1.User" user "User.Eco1")
		(23 "Eco2.User" user "User.Eco2")
		(25 "Edge.Cuts" user "Board Geometry/Outline")
		(27 "Margin" user)
		(31 "F.CrtYd" user "Package Geometry/Place Bound Top")
		(29 "B.CrtYd" user "Package Geometry/Place Bound Bottom")
		(35 "F.Fab" user "Ref Des/Assembly Top")
		(33 "B.Fab" user "Ref Des/Assembly Bottom")
	)
	(footprint ""
		(layer "F.Cu")
		(at 143.97355 -107.795568 180)
		(property "Reference" "C2254"
			(at 0 0 180)
			(layer "F.SilkS")
			(hide yes)
			(effects
				(font
					(size 1.27 1.27)
				)
			)
		)
		(property "Value" ""
			(at 0 0 180)
			(layer "F.Fab")
			(effects
				(font
					(size 1.27 1.27)
				)
			)
		)
		(duplicate_pad_numbers_are_jumpers no)
		(fp_line
			(start 0.7874 0.4064)
			(end -0.7874 0.4064)
			(stroke
				(width 0.1524)
				(type default)
			)
			(layer "F.SilkS")
		)
		(fp_line
			(start 0.7874 -0.4064)
			(end 0.7874 0.4064)
			(stroke
				(width 0.1524)
				(type default)
			)
			(layer "F.SilkS")
		)
		(fp_line
			(start -0.7874 0.4064)
			(end -0.7874 -0.4064)
			(stroke
				(width 0.1524)
				(type default)
			)
			(layer "F.SilkS")
		)
		(fp_line
			(start -0.7874 -0.4064)
			(end 0.7874 -0.4064)
			(stroke
				(width 0.1524)
				(type default)
			)
			(layer "F.SilkS")
		)
		(fp_line
			(start 0.67945 0.3048)
			(end 0.120396 0.3048)
			(stroke
				(width 0.1)
				(type default)
			)
			(layer "F.Fab")
		)
		(fp_line
			(start 0.67945 -0.3048)
			(end 0.67945 0.3048)
			(stroke
				(width 0.1)
				(type default)
			)
			(layer "F.Fab")
		)
		(fp_line
			(start 0.12065 -0.2794)
			(end 0.12065 -0.3048)
			(stroke
				(width 0.1)
				(type default)
			)
			(layer "F.Fab")
		)
		(fp_line
			(start 0.12065 -0.3048)
			(end 0.67945 -0.3048)
			(stroke
				(width 0.1)
				(type default)
			)
			(layer "F.Fab")
		)
		(fp_line
			(start 0.120396 0.3048)
			(end 0.120396 0.2794)
			(stroke
				(width 0.1)
				(type default)
			)
			(layer "F.Fab")
		)
		(fp_line
			(start 0.120396 0.2794)
			(end -0.12065 0.2794)
			(stroke
				(width 0.1)
				(type default)
			)
			(layer "F.Fab")
		)
		(fp_line
			(start -0.12065 0.3048)
			(end -0.67945 0.3048)
			(stroke
				(width 0.1)
				(type default)
			)
			(layer "F.Fab")
		)
		(fp_line
			(start -0.12065 0.2794)
			(end -0.12065 0.3048)
			(stroke
				(width 0.1)
				(type default)
			)
			(layer "F.Fab")
		)
		(fp_line
			(start -0.12065 -0.2794)
			(end 0.12065 -0.2794)
			(stroke
				(width 0.1)
				(type default)
			)
			(layer "F.Fab")
		)
		(fp_line
			(start -0.12065 -0.305054)
			(end -0.12065 -0.2794)
			(stroke
				(width 0.1)
				(type default)
			)
			(layer "F.Fab")
		)
		(fp_line
			(start -0.67945 0.3048)
			(end -0.67945 -0.305054)
			(stroke
				(width 0.1)
				(type default)
			)
			(layer "F.Fab")
		)
		(fp_line
			(start -0.67945 -0.305054)
			(end -0.12065 -0.305054)
			(stroke
				(width 0.1)
				(type default)
			)
			(layer "F.Fab")
		)
		(pad "1" smd circle
			(at -0.40005 0 180)
			(size 0 0)
			(layers "F.Cu" "F.Mask" "F.Paste")
			(net "P0V62_CPU0_ERRS_U306_VREF")
		)
		(pad "2" smd circle
			(at 0.40005 0 180)
			(size 0 0)
			(layers "F.Cu" "F.Mask" "F.Paste")
			(net "GND")
		)
	)
	(footprint ""
		(layer "F.Cu")
		(at 213.933786 -130.923538)
		(property "Reference" "U94"
			(at 1.224026 -1.897888 0)
			(unlocked yes)
			(layer "F.SilkS")
			(effects
				(font
					(size 0.7874 0.5842)
					(thickness 0.1524)
				)
			)
		)
		(property "Value" ""
			(at 0 0 0)
			(layer "F.Fab")
			(effects
				(font
					(size 1.27 1.27)
				)
			)
		)
		(duplicate_pad_numbers_are_jumpers no)
		(fp_line
			(start -1.640078 -1.100074)
			(end -1.640078 1.100074)
			(stroke
				(width 0.1524)
				(type default)
			)
			(layer "F.SilkS")
		)
		(fp_line
			(start -1.640078 1.100074)
			(end 1.640078 1.100074)
			(stroke
				(width 0.1524)
				(type default)
			)
			(layer "F.SilkS")
		)
		(fp_line
			(start 1.640078 -1.100074)
			(end -1.640078 -1.100074)
			(stroke
				(width 0.1524)
				(type default)
			)
			(layer "F.SilkS")
		)
		(fp_line
			(start 1.640078 1.100074)
			(end 1.640078 -1.100074)
			(stroke
				(width 0.1524)
				(type default)
			)
			(layer "F.SilkS")
		)
		(fp_poly
			(pts
				(xy -1.495044 -1.943354) (xy -0.725424 -1.943354) (xy -1.110234 -1.173734)
			)
			(stroke
				(width 0)
				(type default)
			)
			(fill yes)
			(layer "F.SilkS")
		)
		(fp_line
			(start -0.674878 -1.100074)
			(end -0.674878 1.100074)
			(stroke
				(width 0.1)
				(type default)
			)
			(layer "F.Fab")
		)
		(fp_line
			(start -0.674878 1.100074)
			(end 0.674878 1.100074)
			(stroke
				(width 0.1)
				(type default)
			)
			(layer "F.Fab")
		)
		(fp_line
			(start 0.674878 -1.100074)
			(end -0.674878 -1.100074)
			(stroke
				(width 0.1)
				(type default)
			)
			(layer "F.Fab")
		)
		(fp_line
			(start 0.674878 1.100074)
			(end 0.674878 -1.100074)
			(stroke
				(width 0.1)
				(type default)
			)
			(layer "F.Fab")
		)
		(fp_poly
			(pts
				(xy -1.74879 -0.649986) (xy -2.51841 -0.265176) (xy -2.51841 -1.034796)
			)
			(stroke
				(width 0)
				(type default)
			)
			(fill yes)
			(layer "F.Fab")
		)
		(pad "1" smd rect
			(at -0.818896 -0.649986 270)
			(size 0.3556 1.4732)
			(layers "F.Cu" "F.Mask" "F.Paste")
			(net "FM_COMP_P3V3_AUX_ENIN")
		)
		(pad "2" smd rect
			(at -0.818896 0 270)
			(size 0.3556 1.4732)
			(layers "F.Cu" "F.Mask" "F.Paste")
			(net "GND")
		)
		(pad "3" smd rect
			(at -0.818896 0.649986 270)
			(size 0.3556 1.4732)
			(layers "F.Cu" "F.Mask" "F.Paste")
			(net "FM_COMP_P3V3_AUX_VIN")
		)
		(pad "4" smd rect
			(at 0.818896 0.649986 270)
			(size 0.3556 1.4732)
			(layers "F.Cu" "F.Mask" "F.Paste")
			(net "PWRGD_DSW_PWROK_R1")
		)
		(pad "5" smd rect
			(at 0.818896 0 270)
			(size 0.3556 1.4732)
			(layers "F.Cu" "F.Mask" "F.Paste")
			(net "FM_COMP_P3V3_STBY_CEXT")
		)
		(pad "6" smd rect
			(at 0.818896 -0.649986 270)
			(size 0.3556 1.4732)
			(layers "F.Cu" "F.Mask" "F.Paste")
			(net "P3V3_AUX")
		)
	)
)
